# S9S_MB_2U (Grand Teton) — schematic parts with pin connectivity, parts 5880–5880 of 6093; source: Cadence DE-HDL packaged netlist (pstxprt.dat, pstxnet.dat, pstchip.dat)

U2  SOCKET4677_AZIF0045P001C01CS  SOCKET4677_AZIF0045-P001C01CS IO  pkg SOCKET4677_82X64-5XA_H466  page 13  (pins 2935-3260 of 4677)
  DN9  PE2_RX_DN8  IN  = P5E_CPU0_PE2_RX_DN<8>
  DN11  VCCFA_EHV_FIVRA54  POWER  = PVCCFA_EHV_FIVRA_CPU0
  DN13  PE2_TX_DN8  OUT  = P5E_CPU0_PE2_TX_DN<8>
  DN15  VCCFA_EHV_FIVRA55  POWER  = PVCCFA_EHV_FIVRA_CPU0
  DN17  VSS955  POWER  = GND
  DN19  DDR7_SB_DQ23  BI  = M_H_CPU0_SB_DQ<23>
  DN21  DDR7_SB_DQS_DP7  BI  = M_H_CPU0_SB_DQS_DP<7>
  DN23  DDR7_SB_DQ18  BI  = M_H_CPU0_SB_DQ<18>
  DN25  DDR6_SB_DQ15  BI  = M_G_CPU0_SB_DQ<15>
  DN27  DDR6_SB_DQS_DN6  BI  = M_G_CPU0_SB_DQS_DN<6>
  DN29  DDR6_SB_DQ8  BI  = M_G_CPU0_SB_DQ<8>
  DN31  DDR6_SB_DQ7  BI  = M_G_CPU0_SB_DQ<7>
  DN33  DDR6_SB_DQS_DP5  BI  = M_G_CPU0_SB_DQS_DP<5>
  DN35  DDR6_SB_DQ2  BI  = M_G_CPU0_SB_DQ<2>
  DN37  DDR7_SB_CS_N1  OUT  = M_H_CPU0_SB_CS_N<1>
  DN39  VSS957  POWER  = GND
  DN41  DDR7_SB_CA3  OUT  = M_H_CPU0_SB_CA<3>
  DN43  DDR6_SB_CA0  OUT  = M_G_CPU0_SB_CA<0>
  DN45  DDR6_CLK_DP0  OUT  = M_G_CPU0_CLK_DP<0>
  DN48  DDR5_A_RSP0  IN  = M_F_CPU0_SA_RSP<0>
  DN50  DDR6_SA_CA5  OUT  = M_G_CPU0_SA_CA<5>
  DN52  VSS959  POWER  = GND
  DN54  DDR6_SA_CS_N0  OUT  = M_G_CPU0_SA_CS_N<0>
  DN56  DDR6_SA_ECC7  BI  = M_G_CPU0_SA_CB<7>
  DN58  DDR6_SA_DQS_DP9  BI  = M_G_CPU0_SA_DQS_DP<9>
  DN60  DDR6_SA_ECC2  BI  = M_G_CPU0_SA_CB<2>
  DN62  DDR6_SA_DQ31  BI  = M_G_CPU0_SA_DQ<31>
  DN64  DDR6_SA_DQS_DP8  BI  = M_G_CPU0_SA_DQS_DP<8>
  DN66  DDR6_SA_DQ26  BI  = M_G_CPU0_SA_DQ<26>
  DN68  DDR6_SA_DQ15  BI  = M_G_CPU0_SA_DQ<15>
  DN70  DDR6_SA_DQS_DP6  BI  = M_G_CPU0_SA_DQS_DP<6>
  DN72  DDR6_SA_DQ10  BI  = M_G_CPU0_SA_DQ<10>
  DN74  DDR7_SA_DQ7  BI  = M_H_CPU0_SA_DQ<7>
  DN76  DDR7_SA_DQS_DP5  BI  = M_H_CPU0_SA_DQS_DP<5>
  DN78  VSS1143  POWER  = GND
  DN80  UPI3_TX_DP11  OUT  = NC
  DN82  UPI3_TX_DN9  OUT  = NC
  DN84  VSS1147  POWER  = GND
  DN86  PE3_TX_DP6  OUT  = P5E_CPU0_PE3_TX_DP<6>
  DN88  VSS1148  POWER  = GND
  DN90  PE3_RX_DN7  IN  = P5E_CPU0_PE3_RX_DN<7>
  DP2  UPI1_RX_DP7  IN  = UPI_CPU1_CPU0_P0P1_DP<7>
  DP4  VSS1152  POWER  = GND
  DP6  UPI1_TX_DN6  OUT  = UPI_CPU0_CPU1_P1P0_DN<6>
  DP8  VSS1157  POWER  = GND
  DP10  PE2_RX_DP8  IN  = P5E_CPU0_PE2_RX_DP<8>
  DP12  VSS966  POWER  = GND
  DP14  PE2_TX_DN9  OUT  = P5E_CPU0_PE2_TX_DN<9>
  DP16  VSS1149  POWER  = GND
  DP18  VSS968  POWER  = GND
  DP20  DDR7_SB_DQ22  BI  = M_H_CPU0_SB_DQ<22>
  DP22  DDR7_SB_DQ19  BI  = M_H_CPU0_SB_DQ<19>
  DP24  VSS969  POWER  = GND
  DP26  DDR6_SB_DQ14  BI  = M_G_CPU0_SB_DQ<14>
  DP28  DDR6_SB_DQ11  BI  = M_G_CPU0_SB_DQ<11>
  DP30  VSS1150  POWER  = GND
  DP32  DDR6_SB_DQ6  BI  = M_G_CPU0_SB_DQ<6>
  DP34  DDR6_SB_DQ3  BI  = M_G_CPU0_SB_DQ<3>
  DP36  VSS1151  POWER  = GND
  DP38  DDR7_SB_CS_N3  OUT  = M_H_CPU0_SB_CS_N<3>
  DP40  DDR7_SB_CA5  OUT  = M_H_CPU0_SB_CA<5>
  DP42  VSS973  POWER  = GND
  DP44  DDR6_SB_CA1  OUT  = M_G_CPU0_SB_CA<1>
  DP47  DDR5_A_RSP1  IN  = M_F_CPU0_SA_RSP<1>
  DP49  VSS1153  POWER  = GND
  DP51  DDR6_SA_CA3  OUT  = M_G_CPU0_SA_CA<3>
  DP53  DDR6_SA_CS_N1  OUT  = M_G_CPU0_SA_CS_N<1>
  DP55  VSS976  POWER  = GND
  DP57  DDR6_SA_ECC6  BI  = M_G_CPU0_SA_CB<6>
  DP59  DDR6_SA_ECC3  BI  = M_G_CPU0_SA_CB<3>
  DP61  VSS979  POWER  = GND
  DP63  DDR6_SA_DQ30  BI  = M_G_CPU0_SA_DQ<30>
  DP65  DDR6_SA_DQ27  BI  = M_G_CPU0_SA_DQ<27>
  DP67  VSS980  POWER  = GND
  DP69  DDR6_SA_DQ14  BI  = M_G_CPU0_SA_DQ<14>
  DP71  DDR6_SA_DQ11  BI  = M_G_CPU0_SA_DQ<11>
  DP73  VSS1154  POWER  = GND
  DP75  DDR7_SA_DQ6  BI  = M_H_CPU0_SA_DQ<6>
  DP77  DDR7_SA_DQ3  BI  = M_H_CPU0_SA_DQ<3>
  DP79  UPI3_TX_DN8  OUT  = NC
  DP81  VSS1159  POWER  = GND
  DP83  UPI3_TX_DP9  OUT  = NC
  DP85  PE3_TX_DN5  OUT  = P5E_CPU0_PE3_TX_DN<5>
  DP87  VSS1160  POWER  = GND
  DP89  PE3_RX_DN6  IN  = P5E_CPU0_PE3_RX_DN<6>
  DP91  VSS985  POWER  = GND
  DR1  VSS1162  POWER  = GND
  DR3  UPI1_RX_DP6  IN  = UPI_CPU1_CPU0_P0P1_DP<6>
  DR5  VSS998  POWER  = GND
  DR7  UPI1_TX_DP5  OUT  = UPI_CPU0_CPU1_P1P0_DN<5>
  DR9  VSS1187  POWER  = GND
  DR11  PE2_RX_DP9  IN  = P5E_CPU0_PE2_RX_DP<9>
  DR13  VSS1164  POWER  = GND
  DR15  PE2_TX_DP9  OUT  = P5E_CPU0_PE2_TX_DP<9>
  DR17  DDR5_SB_DQ31  BI  = M_F_CPU0_SB_DQ<31>
  DR19  VSS1166  POWER  = GND
  DR21  DDR7_SB_DQS_DN7  BI  = M_H_CPU0_SB_DQS_DN<7>
  DR23  VSS1169  POWER  = GND
  DR25  VSS990  POWER  = GND
  DR27  DDR6_SB_DQS_DP6  BI  = M_G_CPU0_SB_DQS_DP<6>
  DR29  VSS1172  POWER  = GND
  DR31  VSS1173  POWER  = GND
  DR33  DDR6_SB_DQS_DN5  BI  = M_G_CPU0_SB_DQS_DN<5>
  DR35  VSS993  POWER  = GND
  DR37  VSS1174  POWER  = GND
  DR39  DDR7_SB_PAR  OUT  = M_H_CPU0_SB_PAR
  DR41  VSS1175  POWER  = GND
  DR43  VSS1176  POWER  = GND
  DR45  DDR6_CLK_DN0  OUT  = M_G_CPU0_CLK_DN<0>
  DR48  VSS1177  POWER  = GND
  DR50  VSS1178  POWER  = GND
  DR52  DDR6_SA_CA1  OUT  = M_G_CPU0_SA_CA<1>
  DR54  VSS1000  POWER  = GND
  DR56  VSS1179  POWER  = GND
  DR58  DDR6_SA_DQS_DN9  BI  = M_G_CPU0_SA_DQS_DN<9>
  DR60  VSS1002  POWER  = GND
  DR62  VSS1003  POWER  = GND
  DR64  DDR6_SA_DQS_DN8  BI  = M_G_CPU0_SA_DQS_DN<8>
  DR66  VSS1181  POWER  = GND
  DR68  VSS1005  POWER  = GND
  DR70  DDR6_SA_DQS_DN6  BI  = M_G_CPU0_SA_DQS_DN<6>
  DR72  VSS1006  POWER  = GND
  DR74  VSS1182  POWER  = GND
  DR76  DDR7_SA_DQS_DN5  BI  = M_H_CPU0_SA_DQS_DN<5>
  DR78  VSS1183  POWER  = GND
  DR80  UPI3_TX_DP8  OUT  = NC
  DR82  UPI3_TX_DN7  OUT  = NC
  DR84  VSS1184  POWER  = GND
  DR86  PE3_TX_DP5  OUT  = P5E_CPU0_PE3_TX_DP<5>
  DR88  VSS1186  POWER  = GND
  DR90  PE3_RX_DP6  IN  = P5E_CPU0_PE3_RX_DP<6>
  DT2  UPI1_RX_DN6  IN  = UPI_CPU1_CPU0_P0P1_DN<6>
  DT4  VSS1021  POWER  = GND
  DT6  UPI1_TX_DN5  OUT  = UPI_CPU0_CPU1_P1P0_DP<5>
  DT8  VSS1207  POWER  = GND
  DT10  PE2_RX_DN9  IN  = P5E_CPU0_PE2_RX_DN<9>
  DT12  VSS1189  POWER  = GND
  DT14  PE2_TX_DP10  OUT  = P5E_CPU0_PE2_TX_DP<10>
  DT16  VSS1013  POWER  = GND
  DT18  DDR5_SB_DQS_DN3  BI  = M_F_CPU0_SB_DQS_DN<3>
  DT20  VSS1014  POWER  = GND
  DT22  VSS1190  POWER  = GND
  DT24  DDR6_SB_DQS_DP2  BI  = M_G_CPU0_SB_DQS_DP<2>
  DT26  VSS1016  POWER  = GND
  DT28  VSS1191  POWER  = GND
  DT30  DDR5_SB_DQS_DP0  BI  = M_F_CPU0_SB_DQS_DP<0>
  DT32  VSS1192  POWER  = GND
  DT34  VSS1194  POWER  = GND
  DT36  DDR6_SB_DQS_DP9  BI  = M_G_CPU0_SB_DQS_DP<9>
  DT38  VSS1196  POWER  = GND
  DT40  VSS1199  POWER  = GND
  DT42  DDR6_SB_CA6  OUT  = M_G_CPU0_SB_CA<6>
  DT44  VSS1023  POWER  = GND
  DT47  VSS1201  POWER  = GND
  DT49  DDR5_CLK_DP1  OUT  = M_F_CPU0_CLK_DP<1>
  DT51  VSS1025  POWER  = GND
  DT53  VSS1026  POWER  = GND
  DT55  DDR5_SA_DQS_DP3  BI  = M_F_CPU0_SA_DQS_DP<3>
  DT57  VSS1202  POWER  = GND
  DT59  VSS1028  POWER  = GND
  DT61  DDR6_SA_DQS_DN2  BI  = M_G_CPU0_SA_DQS_DN<2>
  DT63  VSS1029  POWER  = GND
  DT65  VSS1203  POWER  = GND
  DT67  DDR5_SA_DQS_DN1  BI  = M_F_CPU0_SA_DQS_DN<1>
  DT69  VSS1204  POWER  = GND
  DT71  VSS1205  POWER  = GND
  DT73  DDR6_SA_DQS_DP0  BI  = M_G_CPU0_SA_DQS_DP<0>
  DT75  VSS1206  POWER  = GND
  DT77  DDR7_SA_DQ1  BI  = M_H_CPU0_SA_DQ<1>
  DT79  VCCFA_EHV_FIVRA58  POWER  = PVCCFA_EHV_FIVRA_CPU0
  DT81  UPI3_TX_DP6  OUT  = NC
  DT83  VSS1036  POWER  = GND
  DT85  VCCFA_EHV_FIVRA59  POWER  = PVCCFA_EHV_FIVRA_CPU0
  DT87  PE3_TX_DN4  OUT  = P5E_CPU0_PE3_TX_DN<4>
  DT89  VCCFA_EHV_FIVRA60  POWER  = PVCCFA_EHV_FIVRA_CPU0
  DT91  PE3_RX_DP5  IN  = P5E_CPU0_PE3_RX_DP<5>
  DU1  UPI1_RX_DN5  IN  = UPI_CPU1_CPU0_P0P1_DN<5>
  DU3  VCCFA_EHV_FIVRA63  POWER  = PVCCFA_EHV_FIVRA_CPU0
  DU5  UPI1_TX_DP4  OUT  = UPI_CPU0_CPU1_P1P0_DP<4>
  DU7  VCCFA_EHV_FIVRA64  POWER  = PVCCFA_EHV_FIVRA_CPU0
  DU9  PE2_RX_DN10  IN  = P5E_CPU0_PE2_RX_DN<10>
  DU11  VCCFA_EHV_FIVRA61  POWER  = PVCCFA_EHV_FIVRA_CPU0
  DU13  PE2_TX_DN10  OUT  = P5E_CPU0_PE2_TX_DN<10>
  DU15  VCCFA_EHV_FIVRA62  POWER  = PVCCFA_EHV_FIVRA_CPU0
  DU17  DDR5_SB_DQ29  BI  = M_F_CPU0_SB_DQ<29>
  DU19  DDR5_SB_DQ25  BI  = M_F_CPU0_SB_DQ<25>
  DU21  VSS1209  POWER  = GND
  DU23  DDR6_SB_DQ20  BI  = M_G_CPU0_SB_DQ<20>
  DU25  DDR6_SB_DQ17  BI  = M_G_CPU0_SB_DQ<17>
  DU27  VSS1211  POWER  = GND
  DU29  DDR5_SB_DQ4  BI  = M_F_CPU0_SB_DQ<4>
  DU31  DDR5_SB_DQ1  BI  = M_F_CPU0_SB_DQ<1>
  DU33  VSS1212  POWER  = GND
  DU35  DDR6_SB_ECC0  BI  = M_G_CPU0_SB_CB<0>
  DU37  DDR6_SB_ECC5  BI  = M_G_CPU0_SB_CB<5>
  DU39  VSS1047  POWER  = GND
  DU41  DDR6_SB_CS_N2  OUT  = M_G_CPU0_SB_CS_N<2>
  DU43  DDR6_SB_CA4  OUT  = M_G_CPU0_SB_CA<4>
  DU45  VSS1048  POWER  = GND
  DU48  DDR6_B_RSP0  IN  = M_G_CPU0_SB_RSP<0>
  DU50  DDR5_SB_CA1  OUT  = M_F_CPU0_SB_CA<1>
  DU52  VSS1050  POWER  = GND
  DU54  DDR5_SA_DQ28  BI  = M_F_CPU0_SA_DQ<28>
  DU56  DDR5_SA_DQ25  BI  = M_F_CPU0_SA_DQ<25>
  DU58  VSS1051  POWER  = GND
  DU60  DDR6_SA_DQ20  BI  = M_G_CPU0_SA_DQ<20>
  DU62  DDR6_SA_DQ17  BI  = M_G_CPU0_SA_DQ<17>
  DU64  VSS1052  POWER  = GND
  DU66  DDR5_SA_DQ12  BI  = M_F_CPU0_SA_DQ<12>
  DU68  DDR5_SA_DQ9  BI  = M_F_CPU0_SA_DQ<9>
  DU70  VSS1054  POWER  = GND
  DU72  DDR6_SA_DQ4  BI  = M_G_CPU0_SA_DQ<4>
  DU74  DDR6_SA_DQ1  BI  = M_G_CPU0_SA_DQ<1>
  DU76  VSS1213  POWER  = GND
  DU78  VSS1214  POWER  = GND
  DU80  UPI3_TX_DN6  OUT  = NC
  DU82  UPI3_TX_DP7  OUT  = NC
  DU84  VSS1215  POWER  = GND
  DU86  PE3_TX_DP4  OUT  = P5E_CPU0_PE3_TX_DP<4>
  DU88  VSS1216  POWER  = GND
  DU90  PE3_RX_DN5  IN  = P5E_CPU0_PE3_RX_DN<5>
  DV2  UPI1_RX_DP5  IN  = UPI_CPU1_CPU0_P0P1_DP<5>
  DV4  VSS1063  POWER  = GND
  DV6  UPI1_TX_DN4  OUT  = UPI_CPU0_CPU1_P1P0_DN<4>
  DV8  VSS1221  POWER  = GND
  DV10  PE2_RX_DP10  IN  = P5E_CPU0_PE2_RX_DP<10>
  DV12  VSS1059  POWER  = GND
  DV14  PE2_TX_DN11  OUT  = P5E_CPU0_PE2_TX_DN<11>
  DV16  VSS1060  POWER  = GND
  DV18  DDR5_SB_DQS_DP3  BI  = M_F_CPU0_SB_DQS_DP<3>
  DV20  DDR5_SB_DQ24  BI  = M_F_CPU0_SB_DQ<24>
  DV22  DDR6_SB_DQ21  BI  = M_G_CPU0_SB_DQ<21>
  DV24  DDR6_SB_DQS_DN2  BI  = M_G_CPU0_SB_DQS_DN<2>
  DV26  DDR6_SB_DQ16  BI  = M_G_CPU0_SB_DQ<16>
  DV28  DDR5_SB_DQ5  BI  = M_F_CPU0_SB_DQ<5>
  DV30  DDR5_SB_DQS_DN0  BI  = M_F_CPU0_SB_DQS_DN<0>
  DV32  DDR5_SB_DQ0  BI  = M_F_CPU0_SB_DQ<0>
  DV34  DDR6_SB_ECC1  BI  = M_G_CPU0_SB_CB<1>
  DV36  DDR6_SB_DQS_DN9  BI  = M_G_CPU0_SB_DQS_DN<9>
  DV38  DDR6_SB_ECC4  BI  = M_G_CPU0_SB_CB<4>
  DV40  DDR6_SB_CS_N3  OUT  = M_G_CPU0_SB_CS_N<3>
  DV42  VSS1064  POWER  = GND
  DV44  DDR6_SB_CA2  OUT  = M_G_CPU0_SB_CA<2>
  DV47  DDR6_B_RSP1  IN  = M_G_CPU0_SB_RSP<1>
  DV49  DDR5_CLK_DN1  OUT  = M_F_CPU0_CLK_DN<1>
  DV51  DDR5_SB_CA0  OUT  = M_F_CPU0_SB_CA<0>
  DV53  DDR5_SA_DQ29  BI  = M_F_CPU0_SA_DQ<29>
  DV55  DDR5_SA_DQS_DN3  BI  = M_F_CPU0_SA_DQS_DN<3>
  DV57  DDR5_SA_DQ24  BI  = M_F_CPU0_SA_DQ<24>
  DV59  DDR6_SA_DQ21  BI  = M_G_CPU0_SA_DQ<21>
  DV61  DDR6_SA_DQS_DP2  BI  = M_G_CPU0_SA_DQS_DP<2>
  DV63  DDR6_SA_DQ16  BI  = M_G_CPU0_SA_DQ<16>
  DV65  DDR5_SA_DQ13  BI  = M_F_CPU0_SA_DQ<13>
  DV67  DDR5_SA_DQS_DP1  BI  = M_F_CPU0_SA_DQS_DP<1>
  DV69  DDR5_SA_DQ8  BI  = M_F_CPU0_SA_DQ<8>
  DV71  DDR6_SA_DQ5  BI  = M_G_CPU0_SA_DQ<5>
  DV73  DDR6_SA_DQS_DN0  BI  = M_G_CPU0_SA_DQS_DN<0>
  DV75  DDR6_SA_DQ0  BI  = M_G_CPU0_SA_DQ<0>
  DV77  VSS1218  POWER  = GND
  DV79  VSS1219  POWER  = GND
  DV81  VSS1222  POWER  = GND
  DV83  VSS1226  POWER  = GND
  DV85  PE3_TX_DN3  OUT  = P5E_CPU0_PE3_TX_DN<3>
  DV87  VSS1227  POWER  = GND
  DV89  PE3_RX_DN4  IN  = P5E_CPU0_PE3_RX_DN<4>
  DV91  VSS1228  POWER  = GND
  DW1  VSS1229  POWER  = GND
  DW3  UPI1_RX_DP4  IN  = UPI_CPU1_CPU0_P0P1_DP<4>
  DW5  VSS1249  POWER  = GND
  DW7  UPI1_TX_DP3  OUT  = UPI_CPU0_CPU1_P1P0_DN<3>
  DW9  VSS1268  POWER  = GND
  DW11  PE2_RX_DP11  IN  = P5E_CPU0_PE2_RX_DP<11>
  DW13  VSS1230  POWER  = GND
  DW15  PE2_TX_DP11  OUT  = P5E_CPU0_PE2_TX_DP<11>
  DW17  VSS1231  POWER  = GND
  DW19  VSS1233  POWER  = GND
  DW21  VSS1077  POWER  = GND
  DW23  VSS1234  POWER  = GND
  DW25  VSS1236  POWER  = GND
  DW27  VSS1238  POWER  = GND
  DW29  VSS1239  POWER  = GND
  DW31  VSS1240  POWER  = GND
  DW33  VSS1241  POWER  = GND
  DW35  VSS1242  POWER  = GND
  DW37  VSS1243  POWER  = GND
  DW39  VSS1244  POWER  = GND
  DW41  VSS1245  POWER  = GND
  DW43  VSS1246  POWER  = GND
  DW45  VSS1247  POWER  = GND
  DW48  VSS1248  POWER  = GND
  DW50  VSS1250  POWER  = GND
  DW52  VSS1251  POWER  = GND
  DW54  VSS1252  POWER  = GND
  DW56  VSS1253  POWER  = GND
  DW58  VSS1254  POWER  = GND
  DW60  VSS1097  POWER  = GND
  DW62  VSS1255  POWER  = GND
  DW64  VSS1256  POWER  = GND
  DW66  VSS1257  POWER  = GND
  DW68  VSS1258  POWER  = GND
  DW70  VSS1259  POWER  = GND
  DW72  VSS1260  POWER  = GND
  DW74  VSS1261  POWER  = GND
  DW76  VSS1262  POWER  = GND
  DW78  DDR7_SA_DQ2  BI  = M_H_CPU0_SA_DQ<2>
  DW80  VSS1263  POWER  = GND
  DW82  VSS1264  POWER  = GND
  DW84  VSS1266  POWER  = GND
  DW86  PE3_TX_DP3  OUT  = P5E_CPU0_PE3_TX_DP<3>
  DW88  VSS1267  POWER  = GND
  DW90  PE3_RX_DP4  IN  = P5E_CPU0_PE3_RX_DP<4>
  DY2  UPI1_RX_DN4  IN  = UPI_CPU1_CPU0_P0P1_DN<4>
  DY4  VSS1115  POWER  = GND
  DY6  UPI1_TX_DN3  OUT  = UPI_CPU0_CPU1_P1P0_DP<3>
  DY8  VSS1270  POWER  = GND
  DY10  PE2_RX_DN11  IN  = P5E_CPU0_PE2_RX_DN<11>
  DY12  VSS1111  POWER  = GND
  DY14  PE2_TX_DP12  OUT  = P5E_CPU0_PE2_TX_DP<12>
  DY16  VSS1112  POWER  = GND
  DY18  DDR5_SB_DQS_DN8  BI  = M_F_CPU0_SB_DQS_DN<8>
  DY20  DDR5_SB_DQ26  BI  = M_F_CPU0_SB_DQ<26>
  DY22  DDR6_SB_DQ23  BI  = M_G_CPU0_SB_DQ<23>
  DY24  DDR6_SB_DQS_DP7  BI  = M_G_CPU0_SB_DQS_DP<7>
  DY26  DDR6_SB_DQ18  BI  = M_G_CPU0_SB_DQ<18>
  DY28  DDR5_SB_DQ7  BI  = M_F_CPU0_SB_DQ<7>
  DY30  DDR5_SB_DQS_DP5  BI  = M_F_CPU0_SB_DQS_DP<5>
